(kicad_pcb
	(version 20260206)
	(generator "pcbnew")
	(generator_version "10.0")
	(general
		(thickness 1.6)
		(legacy_teardrops no)
	)
	(paper "A4")
	(title_block
		(title "03242023_DA0F0TMBIJ0_F0T_Motherboard_J_brd_V01_OCP.brd")
		(comment 1 "Grand Teton / footprints 925-932 of 6105")
	)
	(layers
		(0 "F.Cu" signal "TOP")
		(4 "In1.Cu" signal "GND")
		(6 "In2.Cu" signal "IN1")
		(8 "In3.Cu" signal "GND1")
		(10 "In4.Cu" signal "IN2")
		(12 "In5.Cu" signal "GND2")
		(14 "In6.Cu" signal "IN3")
		(16 "In7.Cu" signal "GND3")
		(18 "In8.Cu" signal "VCC")
		(20 "In9.Cu" signal "VCC1")
		(22 "In10.Cu" signal "GND4")
		(24 "In11.Cu" signal "IN4")
		(26 "In12.Cu" signal "GND5")
		(28 "In13.Cu" signal "IN5")
		(30 "In14.Cu" signal "GND6")
		(32 "In15.Cu" signal "IN6")
		(34 "In16.Cu" signal "GND7")
		(2 "B.Cu" signal "BOTTOM")
		(9 "F.Adhes" user "F.Adhesive")
		(11 "B.Adhes" user "B.Adhesive")
		(13 "F.Paste" user "Package Geometry/Pastemask Top")
		(15 "B.Paste" user "Package Geometry/Pastemask Bottom")
		(5 "F.SilkS" user "Ref Des/Silkscreen Top")
		(7 "B.SilkS" user "Ref Des/Silkscreen Bottom")
		(1 "F.Mask" user "Board Geometry/Soldermask Top")
		(3 "B.Mask" user "Board Geometry/Soldermask Bottom")
		(17 "Dwgs.User" user "User.Drawings")
		(19 "Cmts.User" user "User.Comments")
		(21 "Eco1.User" user "User.Eco1")
		(23 "Eco2.User" user "User.Eco2")
		(25 "Edge.Cuts" user "Board Geometry/Outline")
		(27 "Margin" user)
		(31 "F.CrtYd" user "Package Geometry/Place Bound Top")
		(29 "B.CrtYd" user "Package Geometry/Place Bound Bottom")
		(35 "F.Fab" user "Ref Des/Assembly Top")
		(33 "B.Fab" user "Ref Des/Assembly Bottom")
	)
	(footprint ""
		(layer "F.Cu")
		(at 348.186248 -408.517344 -90)
		(property "Reference" "C930"
			(at 0 0 270)
			(layer "F.SilkS")
			(hide yes)
			(effects
				(font
					(size 1.27 1.27)
				)
			)
		)
		(property "Value" ""
			(at 0 0 270)
			(layer "F.Fab")
			(effects
				(font
					(size 1.27 1.27)
				)
			)
		)
		(duplicate_pad_numbers_are_jumpers no)
		(fp_line
			(start -0.299974 0.150114)
			(end -0.299974 -0.150114)
			(stroke
				(width 0.1)
				(type default)
			)
			(layer "F.Fab")
		)
		(fp_line
			(start 0.299974 0.150114)
			(end -0.299974 0.150114)
			(stroke
				(width 0.1)
				(type default)
			)
			(layer "F.Fab")
		)
		(fp_line
			(start -0.299974 -0.150114)
			(end 0.299974 -0.150114)
			(stroke
				(width 0.1)
				(type default)
			)
			(layer "F.Fab")
		)
		(fp_line
			(start 0.299974 -0.150114)
			(end 0.299974 0.150114)
			(stroke
				(width 0.1)
				(type default)
			)
			(layer "F.Fab")
		)
		(pad "1" smd rect
			(at -0.2667 0 270)
			(size 0.3048 0.381)
			(layers "F.Cu" "F.Mask" "F.Paste")
			(net "P5E_CPU0_PE0_TX_C_DN<1>")
		)
		(pad "2" smd rect
			(at 0.2667 0 270)
			(size 0.3048 0.381)
			(layers "F.Cu" "F.Mask" "F.Paste")
			(net "P5E_CPU0_PE0_TX_DN<1>")
		)
	)
	(footprint ""
		(layer "F.Cu")
		(at 123.6091 -414.283652)
		(property "Reference" "R4490"
			(at 0 0 0)
			(layer "F.SilkS")
			(hide yes)
			(effects
				(font
					(size 1.27 1.27)
				)
			)
		)
		(property "Value" ""
			(at 0 0 0)
			(layer "F.Fab")
			(effects
				(font
					(size 1.27 1.27)
				)
			)
		)
		(duplicate_pad_numbers_are_jumpers no)
		(fp_line
			(start -0.7874 -0.4064)
			(end 0.7874 -0.4064)
			(stroke
				(width 0.1524)
				(type default)
			)
			(layer "F.SilkS")
		)
		(fp_line
			(start -0.7874 0.4064)
			(end -0.7874 -0.4064)
			(stroke
				(width 0.1524)
				(type default)
			)
			(layer "F.SilkS")
		)
		(fp_line
			(start 0.7874 -0.4064)
			(end 0.7874 0.4064)
			(stroke
				(width 0.1524)
				(type default)
			)
			(layer "F.SilkS")
		)
		(fp_line
			(start 0.7874 0.4064)
			(end -0.7874 0.4064)
			(stroke
				(width 0.1524)
				(type default)
			)
			(layer "F.SilkS")
		)
		(fp_line
			(start -0.67945 -0.305054)
			(end -0.12065 -0.305054)
			(stroke
				(width 0.1)
				(type default)
			)
			(layer "F.Fab")
		)
		(fp_line
			(start -0.67945 0.3048)
			(end -0.67945 -0.305054)
			(stroke
				(width 0.1)
				(type default)
			)
			(layer "F.Fab")
		)
		(fp_line
			(start -0.12065 -0.305054)
			(end -0.12065 -0.2794)
			(stroke
				(width 0.1)
				(type default)
			)
			(layer "F.Fab")
		)
		(fp_line
			(start -0.12065 -0.2794)
			(end 0.12065 -0.2794)
			(stroke
				(width 0.1)
				(type default)
			)
			(layer "F.Fab")
		)
		(fp_line
			(start -0.12065 0.2794)
			(end -0.12065 0.3048)
			(stroke
				(width 0.1)
				(type default)
			)
			(layer "F.Fab")
		)
		(fp_line
			(start -0.12065 0.3048)
			(end -0.67945 0.3048)
			(stroke
				(width 0.1)
				(type default)
			)
			(layer "F.Fab")
		)
		(fp_line
			(start 0.120396 0.2794)
			(end -0.12065 0.2794)
			(stroke
				(width 0.1)
				(type default)
			)
			(layer "F.Fab")
		)
		(fp_line
			(start 0.120396 0.3048)
			(end 0.120396 0.2794)
			(stroke
				(width 0.1)
				(type default)
			)
			(layer "F.Fab")
		)
		(fp_line
			(start 0.12065 -0.3048)
			(end 0.67945 -0.3048)
			(stroke
				(width 0.1)
				(type default)
			)
			(layer "F.Fab")
		)
		(fp_line
			(start 0.12065 -0.2794)
			(end 0.12065 -0.3048)
			(stroke
				(width 0.1)
				(type default)
			)
			(layer "F.Fab")
		)
		(fp_line
			(start 0.67945 -0.3048)
			(end 0.67945 0.3048)
			(stroke
				(width 0.1)
				(type default)
			)
			(layer "F.Fab")
		)
		(fp_line
			(start 0.67945 0.3048)
			(end 0.120396 0.3048)
			(stroke
				(width 0.1)
				(type default)
			)
			(layer "F.Fab")
		)
		(pad "1" smd circle
			(at -0.40005 0)
			(size 0 0)
			(layers "F.Cu" "F.Mask" "F.Paste")
			(net "CLK_9ZXL045_SADR0")
		)
		(pad "2" smd circle
			(at 0.40005 0)
			(size 0 0)
			(layers "F.Cu" "F.Mask" "F.Paste")
			(net "GND")
		)
	)
	(footprint ""
		(layer "F.Cu")
		(at 454.742804 -76.588112 90)
		(property "Reference" "PC2343"
			(at 0 0 90)
			(layer "F.SilkS")
			(hide yes)
			(effects
				(font
					(size 1.27 1.27)
				)
			)
		)
		(property "Value" ""
			(at 0 0 90)
			(layer "F.Fab")
			(effects
				(font
					(size 1.27 1.27)
				)
			)
		)
		(duplicate_pad_numbers_are_jumpers no)
		(fp_line
			(start 1.524 -0.762)
			(end 1.524 0.762)
			(stroke
				(width 0.1524)
				(type default)
			)
			(layer "F.SilkS")
		)
		(fp_line
			(start -1.524 -0.762)
			(end 1.524 -0.762)
			(stroke
				(width 0.1524)
				(type default)
			)
			(layer "F.SilkS")
		)
		(fp_line
			(start 1.524 0.762)
			(end -1.524 0.762)
			(stroke
				(width 0.1524)
				(type default)
			)
			(layer "F.SilkS")
		)
		(fp_line
			(start -1.524 0.762)
			(end -1.524 -0.762)
			(stroke
				(width 0.1524)
				(type default)
			)
			(layer "F.SilkS")
		)
		(fp_line
			(start 1.1049 -0.724916)
			(end -1.1049 -0.724916)
			(stroke
				(width 0.1)
				(type default)
			)
			(layer "F.Fab")
		)
		(fp_line
			(start -1.1049 -0.724916)
			(end -1.1049 0.724916)
			(stroke
				(width 0.1)
				(type default)
			)
			(layer "F.Fab")
		)
		(fp_line
			(start 1.1049 0.724916)
			(end 1.1049 -0.724916)
			(stroke
				(width 0.1)
				(type default)
			)
			(layer "F.Fab")
		)
		(fp_line
			(start -1.1049 0.724916)
			(end 1.1049 0.724916)
			(stroke
				(width 0.1)
				(type default)
			)
			(layer "F.Fab")
		)
		(pad "1" smd rect
			(at -0.889 0 270)
			(size 1.016 1.27)
			(layers "F.Cu" "F.Mask" "F.Paste")
			(net "SW_P3V3_AUX_FLT")
		)
		(pad "2" smd rect
			(at 0.889 0 270)
			(size 1.016 1.27)
			(layers "F.Cu" "F.Mask" "F.Paste")
			(net "GND")
		)
	)
	(footprint ""
		(layer "F.Cu")
		(at 325.193914 -26.143712 180)
		(property "Reference" "C610"
			(at 0 0 180)
			(layer "F.SilkS")
			(hide yes)
			(effects
				(font
					(size 1.27 1.27)
				)
			)
		)
		(property "Value" ""
			(at 0 0 180)
			(layer "F.Fab")
			(effects
				(font
					(size 1.27 1.27)
				)
			)
		)
		(duplicate_pad_numbers_are_jumpers no)
		(fp_line
			(start 0.7874 0.4064)
			(end -0.7874 0.4064)
			(stroke
				(width 0.1524)
				(type default)
			)
			(layer "F.SilkS")
		)
		(fp_line
			(start 0.7874 -0.4064)
			(end 0.7874 0.4064)
			(stroke
				(width 0.1524)
				(type default)
			)
			(layer "F.SilkS")
		)
		(fp_line
			(start -0.7874 0.4064)
			(end -0.7874 -0.4064)
			(stroke
				(width 0.1524)
				(type default)
			)
			(layer "F.SilkS")
		)
		(fp_line
			(start -0.7874 -0.4064)
			(end 0.7874 -0.4064)
			(stroke
				(width 0.1524)
				(type default)
			)
			(layer "F.SilkS")
		)
		(fp_line
			(start 0.67945 0.3048)
			(end 0.120396 0.3048)
			(stroke
				(width 0.1)
				(type default)
			)
			(layer "F.Fab")
		)
		(fp_line
			(start 0.67945 -0.3048)
			(end 0.67945 0.3048)
			(stroke
				(width 0.1)
				(type default)
			)
			(layer "F.Fab")
		)
		(fp_line
			(start 0.12065 -0.2794)
			(end 0.12065 -0.3048)
			(stroke
				(width 0.1)
				(type default)
			)
			(layer "F.Fab")
		)
		(fp_line
			(start 0.12065 -0.3048)
			(end 0.67945 -0.3048)
			(stroke
				(width 0.1)
				(type default)
			)
			(layer "F.Fab")
		)
		(fp_line
			(start 0.120396 0.3048)
			(end 0.120396 0.2794)
			(stroke
				(width 0.1)
				(type default)
			)
			(layer "F.Fab")
		)
		(fp_line
			(start 0.120396 0.2794)
			(end -0.12065 0.2794)
			(stroke
				(width 0.1)
				(type default)
			)
			(layer "F.Fab")
		)
		(fp_line
			(start -0.12065 0.3048)
			(end -0.67945 0.3048)
			(stroke
				(width 0.1)
				(type default)
			)
			(layer "F.Fab")
		)
		(fp_line
			(start -0.12065 0.2794)
			(end -0.12065 0.3048)
			(stroke
				(width 0.1)
				(type default)
			)
			(layer "F.Fab")
		)
		(fp_line
			(start -0.12065 -0.2794)
			(end 0.12065 -0.2794)
			(stroke
				(width 0.1)
				(type default)
			)
			(layer "F.Fab")
		)
		(fp_line
			(start -0.12065 -0.305054)
			(end -0.12065 -0.2794)
			(stroke
				(width 0.1)
				(type default)
			)
			(layer "F.Fab")
		)
		(fp_line
			(start -0.67945 0.3048)
			(end -0.67945 -0.305054)
			(stroke
				(width 0.1)
				(type default)
			)
			(layer "F.Fab")
		)
		(fp_line
			(start -0.67945 -0.305054)
			(end -0.12065 -0.305054)
			(stroke
				(width 0.1)
				(type default)
			)
			(layer "F.Fab")
		)
		(pad "1" smd circle
			(at -0.40005 0 180)
			(size 0 0)
			(layers "F.Cu" "F.Mask" "F.Paste")
			(net "RST_SRTCRST_N")
		)
		(pad "2" smd circle
			(at 0.40005 0 180)
			(size 0 0)
			(layers "F.Cu" "F.Mask" "F.Paste")
			(net "GND")
		)
	)
	(footprint ""
		(layer "F.Cu")
		(at 441.099194 -125.035818 90)
		(property "Reference" "C2443"
			(at 0 0 90)
			(layer "F.SilkS")
			(hide yes)
			(effects
				(font
					(size 1.27 1.27)
				)
			)
		)
		(property "Value" ""
			(at 0 0 90)
			(layer "F.Fab")
			(effects
				(font
					(size 1.27 1.27)
				)
			)
		)
		(duplicate_pad_numbers_are_jumpers no)
		(fp_line
			(start 0.7874 -0.4064)
			(end 0.7874 0.4064)
			(stroke
				(width 0.1524)
				(type default)
			)
			(layer "F.SilkS")
		)
		(fp_line
			(start -0.7874 -0.4064)
			(end 0.7874 -0.4064)
			(stroke
				(width 0.1524)
				(type default)
			)
			(layer "F.SilkS")
		)
		(fp_line
			(start 0.7874 0.4064)
			(end -0.7874 0.4064)
			(stroke
				(width 0.1524)
				(type default)
			)
			(layer "F.SilkS")
		)
		(fp_line
			(start -0.7874 0.4064)
			(end -0.7874 -0.4064)
			(stroke
				(width 0.1524)
				(type default)
			)
			(layer "F.SilkS")
		)
		(fp_line
			(start -0.12065 -0.305054)
			(end -0.12065 -0.2794)
			(stroke
				(width 0.1)
				(type default)
			)
			(layer "F.Fab")
		)
		(fp_line
			(start -0.67945 -0.305054)
			(end -0.12065 -0.305054)
			(stroke
				(width 0.1)
				(type default)
			)
			(layer "F.Fab")
		)
		(fp_line
			(start 0.67945 -0.3048)
			(end 0.67945 0.3048)
			(stroke
				(width 0.1)
				(type default)
			)
			(layer "F.Fab")
		)
		(fp_line
			(start 0.12065 -0.3048)
			(end 0.67945 -0.3048)
			(stroke
				(width 0.1)
				(type default)
			)
			(layer "F.Fab")
		)
		(fp_line
			(start 0.12065 -0.2794)
			(end 0.12065 -0.3048)
			(stroke
				(width 0.1)
				(type default)
			)
			(layer "F.Fab")
		)
		(fp_line
			(start -0.12065 -0.2794)
			(end 0.12065 -0.2794)
			(stroke
				(width 0.1)
				(type default)
			)
			(layer "F.Fab")
		)
		(fp_line
			(start 0.120396 0.2794)
			(end -0.12065 0.2794)
			(stroke
				(width 0.1)
				(type default)
			)
			(layer "F.Fab")
		)
		(fp_line
			(start -0.12065 0.2794)
			(end -0.12065 0.3048)
			(stroke
				(width 0.1)
				(type default)
			)
			(layer "F.Fab")
		)
		(fp_line
			(start 0.67945 0.3048)
			(end 0.120396 0.3048)
			(stroke
				(width 0.1)
				(type default)
			)
			(layer "F.Fab")
		)
		(fp_line
			(start 0.120396 0.3048)
			(end 0.120396 0.2794)
			(stroke
				(width 0.1)
				(type default)
			)
			(layer "F.Fab")
		)
		(fp_line
			(start -0.12065 0.3048)
			(end -0.67945 0.3048)
			(stroke
				(width 0.1)
				(type default)
			)
			(layer "F.Fab")
		)
		(fp_line
			(start -0.67945 0.3048)
			(end -0.67945 -0.305054)
			(stroke
				(width 0.1)
				(type default)
			)
			(layer "F.Fab")
		)
		(pad "1" smd circle
			(at -0.40005 0 90)
			(size 0 0)
			(layers "F.Cu" "F.Mask" "F.Paste")
			(net "PVNN_TERM_CPU0")
		)
		(pad "2" smd circle
			(at 0.40005 0 90)
			(size 0 0)
			(layers "F.Cu" "F.Mask" "F.Paste")
			(net "GND")
		)
	)
	(footprint ""
		(layer "F.Cu")
		(at 402.106384 -16.088614 90)
		(property "Reference" "C846"
			(at 0 0 90)
			(layer "F.SilkS")
			(hide yes)
			(effects
				(font
					(size 1.27 1.27)
				)
			)
		)
		(property "Value" ""
			(at 0 0 90)
			(layer "F.Fab")
			(effects
				(font
					(size 1.27 1.27)
				)
			)
		)
		(duplicate_pad_numbers_are_jumpers no)
		(fp_line
			(start 0.299974 -0.150114)
			(end 0.299974 0.150114)
			(stroke
				(width 0.1)
				(type default)
			)
			(layer "F.Fab")
		)
		(fp_line
			(start -0.299974 -0.150114)
			(end 0.299974 -0.150114)
			(stroke
				(width 0.1)
				(type default)
			)
			(layer "F.Fab")
		)
		(fp_line
			(start 0.299974 0.150114)
			(end -0.299974 0.150114)
			(stroke
				(width 0.1)
				(type default)
			)
			(layer "F.Fab")
		)
		(fp_line
			(start -0.299974 0.150114)
			(end -0.299974 -0.150114)
			(stroke
				(width 0.1)
				(type default)
			)
			(layer "F.Fab")
		)
		(pad "1" smd rect
			(at -0.2667 0 90)
			(size 0.3048 0.381)
			(layers "F.Cu" "F.Mask" "F.Paste")
			(net "P5E_CPU0_PE1_TX_C_DN<11>")
		)
		(pad "2" smd rect
			(at 0.2667 0 90)
			(size 0.3048 0.381)
			(layers "F.Cu" "F.Mask" "F.Paste")
			(net "P5E_CPU0_PE1_TX_DN<11>")
		)
	)
	(footprint ""
		(layer "F.Cu")
		(at 249.374406 -92.06484 90)
		(property "Reference" "R1724"
			(at 0 0 90)
			(layer "F.SilkS")
			(hide yes)
			(effects
				(font
					(size 1.27 1.27)
				)
			)
		)
		(property "Value" ""
			(at 0 0 90)
			(layer "F.Fab")
			(effects
				(font
					(size 1.27 1.27)
				)
			)
		)
		(duplicate_pad_numbers_are_jumpers no)
		(fp_line
			(start 0.7874 -0.4064)
			(end 0.7874 0.4064)
			(stroke
				(width 0.1524)
				(type default)
			)
			(layer "F.SilkS")
		)
		(fp_line
			(start -0.7874 -0.4064)
			(end 0.7874 -0.4064)
			(stroke
				(width 0.1524)
				(type default)
			)
			(layer "F.SilkS")
		)
		(fp_line
			(start 0.7874 0.4064)
			(end -0.7874 0.4064)
			(stroke
				(width 0.1524)
				(type default)
			)
			(layer "F.SilkS")
		)
		(fp_line
			(start -0.7874 0.4064)
			(end -0.7874 -0.4064)
			(stroke
				(width 0.1524)
				(type default)
			)
			(layer "F.SilkS")
		)
		(fp_line
			(start -0.12065 -0.305054)
			(end -0.12065 -0.2794)
			(stroke
				(width 0.1)
				(type default)
			)
			(layer "F.Fab")
		)
		(fp_line
			(start -0.67945 -0.305054)
			(end -0.12065 -0.305054)
			(stroke
				(width 0.1)
				(type default)
			)
			(layer "F.Fab")
		)
		(fp_line
			(start 0.67945 -0.3048)
			(end 0.67945 0.3048)
			(stroke
				(width 0.1)
				(type default)
			)
			(layer "F.Fab")
		)
		(fp_line
			(start 0.12065 -0.3048)
			(end 0.67945 -0.3048)
			(stroke
				(width 0.1)
				(type default)
			)
			(layer "F.Fab")
		)
		(fp_line
			(start 0.12065 -0.2794)
			(end 0.12065 -0.3048)
			(stroke
				(width 0.1)
				(type default)
			)
			(layer "F.Fab")
		)
		(fp_line
			(start -0.12065 -0.2794)
			(end 0.12065 -0.2794)
			(stroke
				(width 0.1)
				(type default)
			)
			(layer "F.Fab")
		)
		(fp_line
			(start 0.120396 0.2794)
			(end -0.12065 0.2794)
			(stroke
				(width 0.1)
				(type default)
			)
			(layer "F.Fab")
		)
		(fp_line
			(start -0.12065 0.2794)
			(end -0.12065 0.3048)
			(stroke
				(width 0.1)
				(type default)
			)
			(layer "F.Fab")
		)
		(fp_line
			(start 0.67945 0.3048)
			(end 0.120396 0.3048)
			(stroke
				(width 0.1)
				(type default)
			)
			(layer "F.Fab")
		)
		(fp_line
			(start 0.120396 0.3048)
			(end 0.120396 0.2794)
			(stroke
				(width 0.1)
				(type default)
			)
			(layer "F.Fab")
		)
		(fp_line
			(start -0.12065 0.3048)
			(end -0.67945 0.3048)
			(stroke
				(width 0.1)
				(type default)
			)
			(layer "F.Fab")
		)
		(fp_line
			(start -0.67945 0.3048)
			(end -0.67945 -0.305054)
			(stroke
				(width 0.1)
				(type default)
			)
			(layer "F.Fab")
		)
		(pad "1" smd circle
			(at -0.40005 0 90)
			(size 0 0)
			(layers "F.Cu" "F.Mask" "F.Paste")
			(net "XTAL_CLK_GEN1_25M_X1_R")
		)
		(pad "2" smd circle
			(at 0.40005 0 90)
			(size 0 0)
			(layers "F.Cu" "F.Mask" "F.Paste")
			(net "XTAL_CLK_GEN1_25M_X1")
		)
	)
	(footprint ""
		(layer "F.Cu")
		(at 99.457002 -417.631626 90)
		(property "Reference" "R4202"
			(at 0 0 90)
			(layer "F.SilkS")
			(hide yes)
			(effects
				(font
					(size 1.27 1.27)
				)
			)
		)
		(property "Value" ""
			(at 0 0 90)
			(layer "F.Fab")
			(effects
				(font
					(size 1.27 1.27)
				)
			)
		)
		(duplicate_pad_numbers_are_jumpers no)
		(fp_line
			(start 0.7874 -0.4064)
			(end 0.7874 0.4064)
			(stroke
				(width 0.1524)
				(type default)
			)
			(layer "F.SilkS")
		)
		(fp_line
			(start -0.7874 -0.4064)
			(end 0.7874 -0.4064)
			(stroke
				(width 0.1524)
				(type default)
			)
			(layer "F.SilkS")
		)
		(fp_line
			(start 0.7874 0.4064)
			(end -0.7874 0.4064)
			(stroke
				(width 0.1524)
				(type default)
			)
			(layer "F.SilkS")
		)
		(fp_line
			(start -0.7874 0.4064)
			(end -0.7874 -0.4064)
			(stroke
				(width 0.1524)
				(type default)
			)
			(layer "F.SilkS")
		)
		(fp_line
			(start -0.12065 -0.305054)
			(end -0.12065 -0.2794)
			(stroke
				(width 0.1)
				(type default)
			)
			(layer "F.Fab")
		)
		(fp_line
			(start -0.67945 -0.305054)
			(end -0.12065 -0.305054)
			(stroke
				(width 0.1)
				(type default)
			)
			(layer "F.Fab")
		)
		(fp_line
			(start 0.67945 -0.3048)
			(end 0.67945 0.3048)
			(stroke
				(width 0.1)
				(type default)
			)
			(layer "F.Fab")
		)
		(fp_line
			(start 0.12065 -0.3048)
			(end 0.67945 -0.3048)
			(stroke
				(width 0.1)
				(type default)
			)
			(layer "F.Fab")
		)
		(fp_line
			(start 0.12065 -0.2794)
			(end 0.12065 -0.3048)
			(stroke
				(width 0.1)
				(type default)
			)
			(layer "F.Fab")
		)
		(fp_line
			(start -0.12065 -0.2794)
			(end 0.12065 -0.2794)
			(stroke
				(width 0.1)
				(type default)
			)
			(layer "F.Fab")
		)
		(fp_line
			(start 0.120396 0.2794)
			(end -0.12065 0.2794)
			(stroke
				(width 0.1)
				(type default)
			)
			(layer "F.Fab")
		)
		(fp_line
			(start -0.12065 0.2794)
			(end -0.12065 0.3048)
			(stroke
				(width 0.1)
				(type default)
			)
			(layer "F.Fab")
		)
		(fp_line
			(start 0.67945 0.3048)
			(end 0.120396 0.3048)
			(stroke
				(width 0.1)
				(type default)
			)
			(layer "F.Fab")
		)
		(fp_line
			(start 0.120396 0.3048)
			(end 0.120396 0.2794)
			(stroke
				(width 0.1)
				(type default)
			)
			(layer "F.Fab")
		)
		(fp_line
			(start -0.12065 0.3048)
			(end -0.67945 0.3048)
			(stroke
				(width 0.1)
				(type default)
			)
			(layer "F.Fab")
		)
		(fp_line
			(start -0.67945 0.3048)
			(end -0.67945 -0.305054)
			(stroke
				(width 0.1)
				(type default)
			)
			(layer "F.Fab")
		)
		(pad "1" smd circle
			(at -0.40005 0 90)
			(size 0 0)
			(layers "F.Cu" "F.Mask" "F.Paste")
			(net "P3V3_AUX")
		)
		(pad "2" smd circle
			(at 0.40005 0 90)
			(size 0 0)
			(layers "F.Cu" "F.Mask" "F.Paste")
			(net "U272_2_ADD0")
		)
	)
)
